(kicad_pcb
	(version 20241229)
	(generator "pcbnew")
	(generator_version "9.0")
	(general
		(thickness 1.552)
		(legacy_teardrops no)
	)
	(paper "A4")
	(title_block
		(date "2023-07-25")
		(rev "1.1.4")
		(comment 9 "footprints 210-212 of 379")
	)
	(layers
		(0 "F.Cu" signal)
		(4 "In1.Cu" signal)
		(6 "In2.Cu" signal)
		(8 "In3.Cu" signal)
		(10 "In4.Cu" signal)
		(12 "In5.Cu" signal)
		(14 "In6.Cu" signal)
		(2 "B.Cu" signal)
		(9 "F.Adhes" user "F.Adhesive")
		(11 "B.Adhes" user "B.Adhesive")
		(13 "F.Paste" user)
		(15 "B.Paste" user)
		(5 "F.SilkS" user "F.Silkscreen")
		(7 "B.SilkS" user "B.Silkscreen")
		(1 "F.Mask" user)
		(3 "B.Mask" user)
		(17 "Dwgs.User" user "User.Drawings")
		(19 "Cmts.User" user "User.Comments")
		(21 "Eco1.User" user "User.Eco1")
		(23 "Eco2.User" user "User.Eco2")
		(25 "Edge.Cuts" user)
		(27 "Margin" user)
		(31 "F.CrtYd" user "F.Courtyard")
		(29 "B.CrtYd" user "B.Courtyard")
		(35 "F.Fab" user)
		(33 "B.Fab" user)
	)
	(footprint "antmicro-footprints:SOT-23-3"
		(layer "F.Cu")
		(at 125.03 113.65 -90)
		(property "Reference" "Q6"
			(at 0.89 -1.5 90)
			(layer "F.SilkS")
			(effects
				(font
					(size 0.65 0.65)
					(thickness 0.15)
				)
				(justify right bottom)
			)
		)
		(property "Value" "2N7002_SOT-23-3"
			(at -1.9 2.7 90)
			(layer "F.Fab")
			(hide yes)
			(effects
				(font
					(size 0.7 0.7)
					(thickness 0.15)
				)
				(justify right bottom)
			)
		)
		(property "Datasheet" "https://www.onsemi.com/pub/Collateral/NDS7002A-D.PDF"
			(at 0 0 270)
			(layer "F.Fab")
			(hide yes)
			(effects
				(font
					(size 1.27 1.27)
					(thickness 0.15)
				)
			)
		)
		(property "Description" "Power MOSFET, N Channel, 60 V, 115 mA, 1.2 ohm, SOT-23, Surface Mount"
			(at 0 0 270)
			(layer "F.Fab")
			(hide yes)
			(effects
				(font
					(size 1.27 1.27)
					(thickness 0.15)
				)
			)
		)
		(property "Author" "Antmicro"
			(at 11.38 238.68 0)
			(layer "F.Fab")
			(hide yes)
			(effects
				(font
					(size 1 1)
					(thickness 0.15)
				)
			)
		)
		(property "License" "Apache-2.0"
			(at 11.38 238.68 0)
			(layer "F.Fab")
			(hide yes)
			(effects
				(font
					(size 1 1)
					(thickness 0.15)
				)
			)
		)
		(property "MPN" "2N7002"
			(at 11.38 238.68 0)
			(layer "F.Fab")
			(hide yes)
			(effects
				(font
					(size 1 1)
					(thickness 0.15)
				)
			)
		)
		(property "Manufacturer" "ON Semiconductor"
			(at 11.38 238.68 0)
			(layer "F.Fab")
			(hide yes)
			(effects
				(font
					(size 1 1)
					(thickness 0.15)
				)
			)
		)
		(sheetname "/FPGA/")
		(sheetfile "fpga.kicad_sch")
		(attr smd)
		(fp_line
			(start -0.7 1.5)
			(end -0.7 1.35)
			(stroke
				(width 0.15)
				(type solid)
			)
			(layer "F.SilkS")
		)
		(fp_line
			(start 0.7 1.5)
			(end -0.7 1.5)
			(stroke
				(width 0.15)
				(type solid)
			)
			(layer "F.SilkS")
		)
		(fp_line
			(start 0.7 0.4)
			(end 0.7 1.5)
			(stroke
				(width 0.15)
				(type solid)
			)
			(layer "F.SilkS")
		)
		(fp_line
			(start 0.7 -0.4)
			(end 0.7 -1.5)
			(stroke
				(width 0.15)
				(type solid)
			)
			(layer "F.SilkS")
		)
		(fp_line
			(start -1.45 -1.35)
			(end -0.85 -1.35)
			(stroke
				(width 0.15)
				(type solid)
			)
			(layer "F.SilkS")
		)
		(fp_line
			(start -0.85 -1.35)
			(end -0.7 -1.5)
			(stroke
				(width 0.15)
				(type solid)
			)
			(layer "F.SilkS")
		)
		(fp_line
			(start 0.7 -1.5)
			(end -0.7 -1.5)
			(stroke
				(width 0.15)
				(type solid)
			)
			(layer "F.SilkS")
		)
		(fp_line
			(start -0.85 1.65)
			(end -0.85 1.4)
			(stroke
				(width 0.05)
				(type solid)
			)
			(layer "F.CrtYd")
		)
		(fp_line
			(start 0.85 1.65)
			(end -0.85 1.65)
			(stroke
				(width 0.05)
				(type solid)
			)
			(layer "F.CrtYd")
		)
		(fp_line
			(start -1.75 1.4)
			(end -1.75 0.5)
			(stroke
				(width 0.05)
				(type solid)
			)
			(layer "F.CrtYd")
		)
		(fp_line
			(start -0.85 1.4)
			(end -1.75 1.4)
			(stroke
				(width 0.05)
				(type solid)
			)
			(layer "F.CrtYd")
		)
		(fp_line
			(start -1.75 0.5)
			(end -0.85 0.5)
			(stroke
				(width 0.05)
				(type solid)
			)
			(layer "F.CrtYd")
		)
		(fp_line
			(start -0.85 0.5)
			(end -0.85 -0.5)
			(stroke
				(width 0.05)
				(type solid)
			)
			(layer "F.CrtYd")
		)
		(fp_line
			(start 0.85 0.45)
			(end 0.85 1.65)
			(stroke
				(width 0.05)
				(type solid)
			)
			(layer "F.CrtYd")
		)
		(fp_line
			(start 1.75 0.45)
			(end 0.85 0.45)
			(stroke
				(width 0.05)
				(type solid)
			)
			(layer "F.CrtYd")
		)
		(fp_line
			(start 0.825 -0.45)
			(end 1.75 -0.45)
			(stroke
				(width 0.05)
				(type solid)
			)
			(layer "F.CrtYd")
		)
		(fp_line
			(start 1.75 -0.45)
			(end 1.75 0.45)
			(stroke
				(width 0.05)
				(type solid)
			)
			(layer "F.CrtYd")
		)
		(fp_line
			(start -1.75 -0.5)
			(end -1.75 -1.4)
			(stroke
				(width 0.05)
				(type solid)
			)
			(layer "F.CrtYd")
		)
		(fp_line
			(start -0.85 -0.5)
			(end -1.75 -0.5)
			(stroke
				(width 0.05)
				(type solid)
			)
			(layer "F.CrtYd")
		)
		(fp_line
			(start -0.9 -1.4)
			(end -1.75 -1.4)
			(stroke
				(width 0.05)
				(type solid)
			)
			(layer "F.CrtYd")
		)
		(fp_line
			(start -0.9 -1.6)
			(end -0.9 -1.4)
			(stroke
				(width 0.05)
				(type solid)
			)
			(layer "F.CrtYd")
		)
		(fp_line
			(start -0.9 -1.6)
			(end 0.825 -1.6)
			(stroke
				(width 0.05)
				(type solid)
			)
			(layer "F.CrtYd")
		)
		(fp_line
			(start 0.825 -1.6)
			(end 0.825 -0.45)
			(stroke
				(width 0.05)
				(type solid)
			)
			(layer "F.CrtYd")
		)
		(fp_line
			(start -0.712 1.519)
			(end 0.688 1.519)
			(stroke
				(width 0.15)
				(type solid)
			)
			(layer "F.Fab")
		)
		(fp_line
			(start 0.688 1.519)
			(end 0.688 -1.52)
			(stroke
				(width 0.15)
				(type solid)
			)
			(layer "F.Fab")
		)
		(fp_line
			(start -0.712 -1.325)
			(end -0.712 1.523)
			(stroke
				(width 0.15)
				(type solid)
			)
			(layer "F.Fab")
		)
		(fp_line
			(start -0.437 -1.526)
			(end -0.712 -1.325)
			(stroke
				(width 0.15)
				(type solid)
			)
			(layer "F.Fab")
		)
		(fp_line
			(start -0.437 -1.526)
			(end 0.688 -1.526)
			(stroke
				(width 0.15)
				(type solid)
			)
			(layer "F.Fab")
		)
		(pad "1" smd roundrect
			(at -1.1 -0.951 270)
			(size 1 0.6)
			(layers "F.Cu" "F.Mask" "F.Paste")
			(roundrect_rratio 0.15)
			(net 261 "Net-(Q6-G)")
			(pinfunction "G")
			(pintype "input")
		)
		(pad "2" smd roundrect
			(at -1.1 0.949 270)
			(size 1 0.6)
			(layers "F.Cu" "F.Mask" "F.Paste")
			(roundrect_rratio 0.15)
			(net 1 "GND")
			(pinfunction "S")
			(pintype "passive")
		)
		(pad "3" smd roundrect
			(at 1.1 -0.0005 270)
			(size 1 0.6)
			(layers "F.Cu" "F.Mask" "F.Paste")
			(roundrect_rratio 0.15)
			(net 66 "Net-(D5-C)")
			(pinfunction "D")
			(pintype "passive")
		)
	)
	(footprint "antmicro-footprints:LED_0603_1608Metric_G"
		(layer "F.Cu")
		(at 172.69 77.73 180)
		(descr "LED SMD 0603 Green")
		(tags "LED SMD 0603 Green")
		(property "Reference" "D11"
			(at -1.04 1.66 0)
			(layer "F.SilkS")
			(effects
				(font
					(size 0.65 0.65)
					(thickness 0.15)
				)
				(justify right top)
			)
		)
		(property "Value" "LED_G_0603_LTST-C190GKT"
			(at 0 1.6 0)
			(layer "F.Fab")
			(hide yes)
			(effects
				(font
					(size 0.7 0.7)
					(thickness 0.15)
				)
				(justify right top)
			)
		)
		(property "Datasheet" "https://media.digikey.com/pdf/Data%20Sheets/Lite-On%20PDFs/LTST-C190GKT.pdf"
			(at 0 0 0)
			(layer "F.Fab")
			(hide yes)
			(effects
				(font
					(size 1.27 1.27)
					(thickness 0.15)
				)
			)
		)
		(property "Description" "LED, Green, SMD, 0603, 20 mA, 2.1 V, 569 nm"
			(at 0 0 0)
			(layer "F.Fab")
			(hide yes)
			(effects
				(font
					(size 1.27 1.27)
					(thickness 0.15)
				)
			)
		)
		(property "Author" "Antmicro"
			(at 0 0 0)
			(layer "F.Fab")
			(hide yes)
			(effects
				(font
					(size 1 1)
					(thickness 0.15)
				)
			)
		)
		(property "License" "Apache-2.0"
			(at 0 0 0)
			(layer "F.Fab")
			(hide yes)
			(effects
				(font
					(size 1 1)
					(thickness 0.15)
				)
			)
		)
		(property "MPN" "LTST-C190GKT"
			(at 0 0 0)
			(layer "F.Fab")
			(hide yes)
			(effects
				(font
					(size 1 1)
					(thickness 0.15)
				)
			)
		)
		(property "Manufacturer" "Lite-On"
			(at 0 0 0)
			(layer "F.Fab")
			(hide yes)
			(effects
				(font
					(size 1 1)
					(thickness 0.15)
				)
			)
		)
		(property "Color" "Green"
			(at 0 0 180)
			(unlocked yes)
			(layer "F.Fab")
			(hide yes)
			(effects
				(font
					(size 1 1)
					(thickness 0.15)
				)
			)
		)
		(sheetname "/Peripherals/")
		(sheetfile "peripherals.kicad_sch")
		(attr smd)
		(fp_line
			(start 0.22 0.35)
			(end -0.22 0.35)
			(stroke
				(width 0.15)
				(type solid)
			)
			(layer "F.SilkS")
		)
		(fp_line
			(start 0.22 -0.35)
			(end -0.22 -0.35)
			(stroke
				(width 0.15)
				(type solid)
			)
			(layer "F.SilkS")
		)
		(fp_line
			(start 0.105328 0.201008)
			(end 0.105328 -0.198992)
			(stroke
				(width 0.1)
				(type solid)
			)
			(layer "F.SilkS")
		)
		(fp_line
			(start 0.105328 0.201008)
			(end -0.094672 0.001008)
			(stroke
				(width 0.1)
				(type solid)
			)
			(layer "F.SilkS")
		)
		(fp_line
			(start 0.105328 0.001008)
			(end 0.24 0.001)
			(stroke
				(width 0.1)
				(type solid)
			)
			(layer "F.SilkS")
		)
		(fp_line
			(start -0.094672 0.201008)
			(end -0.094672 -0.198992)
			(stroke
				(width 0.1)
				(type solid)
			)
			(layer "F.SilkS")
		)
		(fp_line
			(start -0.094672 0.001008)
			(end 0.105328 -0.198992)
			(stroke
				(width 0.1)
				(type solid)
			)
			(layer "F.SilkS")
		)
		(fp_line
			(start -0.094672 0.001008)
			(end -0.24 0.001008)
			(stroke
				(width 0.1)
				(type solid)
			)
			(layer "F.SilkS")
		)
		(fp_line
			(start -1.18 -0.319)
			(end -1.18 0.321)
			(stroke
				(width 0.15)
				(type solid)
			)
			(layer "F.SilkS")
		)
		(fp_rect
			(start 1.25 0.65)
			(end -1.25 -0.65)
			(stroke
				(width 0.05)
				(type solid)
			)
			(fill no)
			(layer "F.CrtYd")
		)
		(fp_line
			(start 0.599 0)
			(end 0.201 0)
			(stroke
				(width 0.15)
				(type solid)
			)
			(layer "F.Fab")
		)
		(fp_line
			(start 0.201 0.2)
			(end 0.201 0)
			(stroke
				(width 0.15)
				(type solid)
			)
			(layer "F.Fab")
		)
		(fp_line
			(start 0.201 0)
			(end 0.201 -0.202)
			(stroke
				(width 0.15)
				(type solid)
			)
			(layer "F.Fab")
		)
		(fp_line
			(start 0.201 -0.202)
			(end -0.101 0)
			(stroke
				(width 0.15)
				(type solid)
			)
			(layer "F.Fab")
		)
		(fp_line
			(start -0.101 0)
			(end 0.201 0.2)
			(stroke
				(width 0.15)
				(type solid)
			)
			(layer "F.Fab")
		)
		(fp_line
			(start -0.199 0.2)
			(end -0.199 0.1)
			(stroke
				(width 0.15)
				(type solid)
			)
			(layer "F.Fab")
		)
		(fp_line
			(start -0.199 0)
			(end -0.597 0)
			(stroke
				(width 0.15)
				(type solid)
			)
			(layer "F.Fab")
		)
		(fp_line
			(start -0.199 -0.202)
			(end -0.199 0.1)
			(stroke
				(width 0.15)
				(type solid)
			)
			(layer "F.Fab")
		)
		(fp_rect
			(start 0.848 0.4)
			(end -0.85 -0.402)
			(stroke
				(width 0.15)
				(type solid)
			)
			(fill no)
			(layer "F.Fab")
		)
		(fp_text user "${REFERENCE}"
			(at -1.4224 5.999 0)
			(layer "F.Fab")
			(effects
				(font
					(size 0.7 0.7)
					(thickness 0.15)
				)
				(justify right top)
			)
		)
		(fp_text user "Author: Antmicro"
			(at -1.4224 4.799 0)
			(layer "F.Fab")
			(effects
				(font
					(size 0.7 0.7)
					(thickness 0.15)
				)
				(justify right top)
			)
		)
		(fp_text user "License: Apache-2.0"
			(at -1.4224 3.599 0)
			(layer "F.Fab")
			(effects
				(font
					(size 0.7 0.7)
					(thickness 0.15)
				)
				(justify right top)
			)
		)
		(pad "1" smd roundrect
			(at -0.7 0)
			(size 0.8 1)
			(layers "F.Cu" "F.Mask" "F.Paste")
			(roundrect_rratio 0.2)
			(net 1 "GND")
			(pinfunction "C")
			(pintype "passive")
		)
		(pad "2" smd roundrect
			(at 0.7 0)
			(size 0.8 1)
			(layers "F.Cu" "F.Mask" "F.Paste")
			(roundrect_rratio 0.2)
			(net 257 "Net-(D11-A)")
			(pinfunction "A")
			(pintype "passive")
		)
	)
	(footprint "antmicro-footprints:SOT-23-6"
		(layer "F.Cu")
		(at 162.53 86.65 -90)
		(property "Reference" "U14"
			(at -1.75 -2 270)
			(layer "F.SilkS")
			(effects
				(font
					(size 0.65 0.65)
					(thickness 0.15)
				)
				(justify left bottom)
			)
		)
		(property "Value" "DIO7553ST6"
			(at -1.75 2.75 270)
			(layer "F.Fab")
			(hide yes)
			(effects
				(font
					(size 0.7 0.7)
					(thickness 0.15)
				)
				(justify left bottom)
			)
		)
		(property "Datasheet" "https://www.mouser.com/datasheet/2/802/7e5c577022fb784effcb3cdb25b437c0-1815562.pdf"
			(at 0 0 270)
			(layer "F.Fab")
			(hide yes)
			(effects
				(font
					(size 1.27 1.27)
					(thickness 0.15)
				)
			)
		)
		(property "Description" "Power switch"
			(at 0 0 270)
			(layer "F.Fab")
			(hide yes)
			(effects
				(font
					(size 1.27 1.27)
					(thickness 0.15)
				)
			)
		)
		(property "Author" "Antmicro"
			(at 75.88 249.18 0)
			(layer "F.Fab")
			(hide yes)
			(effects
				(font
					(size 1 1)
					(thickness 0.15)
				)
			)
		)
		(property "License" "Apache-2.0"
			(at 75.88 249.18 0)
			(layer "F.Fab")
			(hide yes)
			(effects
				(font
					(size 1 1)
					(thickness 0.15)
				)
			)
		)
		(property "MPN" "DIO7553ST6"
			(at 75.88 249.18 0)
			(layer "F.Fab")
			(hide yes)
			(effects
				(font
					(size 1 1)
					(thickness 0.15)
				)
			)
		)
		(property "Manufacturer" "DIOO Microcircuits"
			(at 75.88 249.18 0)
			(layer "F.Fab")
			(hide yes)
			(effects
				(font
					(size 1 1)
					(thickness 0.15)
				)
			)
		)
		(sheetname "/Peripherals/")
		(sheetfile "peripherals.kicad_sch")
		(attr smd)
		(fp_line
			(start -1.45 0.643)
			(end -1.45 0.343)
			(stroke
				(width 0.12)
				(type solid)
			)
			(layer "F.SilkS")
		)
		(fp_line
			(start 1.3 0.643)
			(end 1.45 0.643)
			(stroke
				(width 0.12)
				(type solid)
			)
			(layer "F.SilkS")
		)
		(fp_line
			(start 1.45 0.643)
			(end 1.45 0.343)
			(stroke
				(width 0.12)
				(type solid)
			)
			(layer "F.SilkS")
		)
		(fp_line
			(start -1.45 -0.757)
			(end -1.45 -0.457)
			(stroke
				(width 0.12)
				(type solid)
			)
			(layer "F.SilkS")
		)
		(fp_line
			(start -1.3 -0.757)
			(end -1.45 -0.757)
			(stroke
				(width 0.12)
				(type solid)
			)
			(layer "F.SilkS")
		)
		(fp_line
			(start 1.3 -0.757)
			(end 1.45 -0.757)
			(stroke
				(width 0.12)
				(type solid)
			)
			(layer "F.SilkS")
		)
		(fp_line
			(start 1.45 -0.757)
			(end 1.45 -0.457)
			(stroke
				(width 0.12)
				(type solid)
			)
			(layer "F.SilkS")
		)
		(fp_rect
			(start -1.55 -1.85)
			(end 1.55 1.75)
			(stroke
				(width 0.05)
				(type solid)
			)
			(fill no)
			(layer "F.CrtYd")
		)
		(fp_line
			(start -1.5 0.643)
			(end -1.5 -0.757)
			(stroke
				(width 0.1)
				(type solid)
			)
			(layer "F.Fab")
		)
		(fp_line
			(start 1.5 0.643)
			(end -1.5 0.643)
			(stroke
				(width 0.1)
				(type solid)
			)
			(layer "F.Fab")
		)
		(fp_line
			(start -1.5 -0.757)
			(end 1.5 -0.757)
			(stroke
				(width 0.1)
				(type solid)
			)
			(layer "F.Fab")
		)
		(fp_line
			(start 1.5 -0.757)
			(end 1.5 0.643)
			(stroke
				(width 0.1)
				(type solid)
			)
			(layer "F.Fab")
		)
		(fp_text user "."
			(at -1.76 2.05 90)
			(layer "F.SilkS")
			(effects
				(font
					(size 1 1)
					(thickness 0.15)
				)
			)
		)
		(fp_text user "License: Apache-2.0"
			(at -1.75 6.5 270)
			(layer "F.Fab")
			(effects
				(font
					(size 0.7 0.7)
					(thickness 0.15)
				)
				(justify left bottom)
			)
		)
		(fp_text user "${REFERENCE}"
			(at -1.75 4 270)
			(layer "F.Fab")
			(effects
				(font
					(size 0.7 0.7)
					(thickness 0.15)
				)
				(justify left bottom)
			)
		)
		(fp_text user "Author: Antmicro"
			(at -1.829 5.25 270)
			(layer "F.Fab")
			(effects
				(font
					(size 0.7 0.7)
					(thickness 0.15)
				)
				(justify left bottom)
			)
		)
		(pad "1" smd roundrect
			(at -0.954 1.1 270)
			(size 0.55 1)
			(layers "F.Cu" "F.Mask" "F.Paste")
			(roundrect_rratio 0.15)
			(net 14 "+5V")
			(pinfunction "IN")
			(pintype "power_in")
		)
		(pad "2" smd roundrect
			(at -0.003 1.1 270)
			(size 0.55 1)
			(layers "F.Cu" "F.Mask" "F.Paste")
			(roundrect_rratio 0.15)
			(net 1 "GND")
			(pinfunction "GND")
			(pintype "power_in")
		)
		(pad "3" smd roundrect
			(at 0.947 1.1 270)
			(size 0.55 1)
			(layers "F.Cu" "F.Mask" "F.Paste")
			(roundrect_rratio 0.15)
			(net 307 "/Peripherals/FFC1_PEN")
			(pinfunction "EN")
			(pintype "input")
		)
		(pad "4" smd roundrect
			(at 0.947 -1.214 270)
			(size 0.55 1)
			(layers "F.Cu" "F.Mask" "F.Paste")
			(roundrect_rratio 0.15)
			(net 351 "Net-(U13-~{FAULT})")
			(pinfunction "~{FAULT}")
			(pintype "output")
		)
		(pad "5" smd roundrect
			(at -0.003 -1.214 270)
			(size 0.55 1)
			(layers "F.Cu" "F.Mask" "F.Paste")
			(roundrect_rratio 0.15)
			(net 354 "Net-(U14-ILIM)")
			(pinfunction "ILIM")
			(pintype "passive")
		)
		(pad "6" smd roundrect
			(at -0.954 -1.214 270)
			(size 0.55 1)
			(layers "F.Cu" "F.Mask" "F.Paste")
			(roundrect_rratio 0.15)
			(net 16 "/Peripherals/FFC1_5V")
			(pinfunction "OUT")
			(pintype "power_out")
		)
	)
)
